# S9S_MB_2U (Grand Teton) — schematic netlist excerpt (pin names and nets, part order shuffled) for the footprints in the layout excerpt that follows; sources: Cadence DE-HDL packaged netlist, KiCad conversion of 03242023_DA0F0TMBIJ0_F0T_Motherboard_J_brd_V01_OCP.brd

R4803  Q_RES  0 5% CHIP  pkg 0402LF  page 189 : A = P1V05_PCH_AUX ; B = P1V05_PCH_PLL_AUX
R1498  Q_RES  1K 1% EMPTY  pkg 0402LF  page 200 : A = P1V05_PCH_AUX ; B = FM_BIOS_ADV_FUNCTIONS

(kicad_pcb
	(version 20260206)
	(generator "pcbnew")
	(generator_version "10.0")
	(general
		(thickness 1.6)
		(legacy_teardrops no)
	)
	(paper "A4")
	(title_block
		(title "03242023_DA0F0TMBIJ0_F0T_Motherboard_J_brd_V01_OCP.brd")
		(comment 1 "Grand Teton / footprints 4782-4783 of 6105")
	)
	(layers
		(0 "F.Cu" signal "TOP")
		(4 "In1.Cu" signal "GND")
		(6 "In2.Cu" signal "IN1")
		(8 "In3.Cu" signal "GND1")
		(10 "In4.Cu" signal "IN2")
		(12 "In5.Cu" signal "GND2")
		(14 "In6.Cu" signal "IN3")
		(16 "In7.Cu" signal "GND3")
		(18 "In8.Cu" signal "VCC")
		(20 "In9.Cu" signal "VCC1")
		(22 "In10.Cu" signal "GND4")
		(24 "In11.Cu" signal "IN4")
		(26 "In12.Cu" signal "GND5")
		(28 "In13.Cu" signal "IN5")
		(30 "In14.Cu" signal "GND6")
		(32 "In15.Cu" signal "IN6")
		(34 "In16.Cu" signal "GND7")
		(2 "B.Cu" signal "BOTTOM")
		(9 "F.Adhes" user "F.Adhesive")
		(11 "B.Adhes" user "B.Adhesive")
		(13 "F.Paste" user "Package Geometry/Pastemask Top")
		(15 "B.Paste" user "Package Geometry/Pastemask Bottom")
		(5 "F.SilkS" user "Ref Des/Silkscreen Top")
		(7 "B.SilkS" user "Ref Des/Silkscreen Bottom")
		(1 "F.Mask" user "Board Geometry/Soldermask Top")
		(3 "B.Mask" user "Board Geometry/Soldermask Bottom")
		(17 "Dwgs.User" user "User.Drawings")
		(19 "Cmts.User" user "User.Comments")
		(21 "Eco1.User" user "User.Eco1")
		(23 "Eco2.User" user "User.Eco2")
		(25 "Edge.Cuts" user "Board Geometry/Outline")
		(27 "Margin" user)
		(31 "F.CrtYd" user "Package Geometry/Place Bound Top")
		(29 "B.CrtYd" user "Package Geometry/Place Bound Bottom")
		(35 "F.Fab" user "Ref Des/Assembly Top")
		(33 "B.Fab" user "Ref Des/Assembly Bottom")
	)
	(footprint ""
		(layer "B.Cu")
		(at 338.4042 -52.0446 180)
		(property "Reference" "R4803"
			(at 0 0 0)
			(layer "B.SilkS")
			(hide yes)
			(effects
				(font
					(size 1.27 1.27)
				)
				(justify mirror)
			)
		)
		(property "Value" ""
			(at 0 0 0)
			(layer "B.Fab")
			(effects
				(font
					(size 1.27 1.27)
				)
				(justify mirror)
			)
		)
		(duplicate_pad_numbers_are_jumpers no)
		(fp_line
			(start 0.7874 0.4064)
			(end 0.7874 -0.4064)
			(stroke
				(width 0.1524)
				(type default)
			)
			(layer "B.SilkS")
		)
		(fp_line
			(start 0.7874 -0.4064)
			(end -0.7874 -0.4064)
			(stroke
				(width 0.1524)
				(type default)
			)
			(layer "B.SilkS")
		)
		(fp_line
			(start -0.7874 0.4064)
			(end 0.7874 0.4064)
			(stroke
				(width 0.1524)
				(type default)
			)
			(layer "B.SilkS")
		)
		(fp_line
			(start -0.7874 -0.4064)
			(end -0.7874 0.4064)
			(stroke
				(width 0.1524)
				(type default)
			)
			(layer "B.SilkS")
		)
		(fp_line
			(start 0.67945 0.3048)
			(end 0.67945 -0.305054)
			(stroke
				(width 0.1)
				(type default)
			)
			(layer "B.Fab")
		)
		(fp_line
			(start 0.67945 -0.305054)
			(end 0.12065 -0.305054)
			(stroke
				(width 0.1)
				(type default)
			)
			(layer "B.Fab")
		)
		(fp_line
			(start 0.12065 0.3048)
			(end 0.67945 0.3048)
			(stroke
				(width 0.1)
				(type default)
			)
			(layer "B.Fab")
		)
		(fp_line
			(start 0.12065 0.2794)
			(end 0.12065 0.3048)
			(stroke
				(width 0.1)
				(type default)
			)
			(layer "B.Fab")
		)
		(fp_line
			(start 0.12065 -0.2794)
			(end -0.12065 -0.2794)
			(stroke
				(width 0.1)
				(type default)
			)
			(layer "B.Fab")
		)
		(fp_line
			(start 0.12065 -0.305054)
			(end 0.12065 -0.2794)
			(stroke
				(width 0.1)
				(type default)
			)
			(layer "B.Fab")
		)
		(fp_line
			(start -0.120396 0.3048)
			(end -0.120396 0.2794)
			(stroke
				(width 0.1)
				(type default)
			)
			(layer "B.Fab")
		)
		(fp_line
			(start -0.120396 0.2794)
			(end 0.12065 0.2794)
			(stroke
				(width 0.1)
				(type default)
			)
			(layer "B.Fab")
		)
		(fp_line
			(start -0.12065 -0.2794)
			(end -0.12065 -0.3048)
			(stroke
				(width 0.1)
				(type default)
			)
			(layer "B.Fab")
		)
		(fp_line
			(start -0.12065 -0.3048)
			(end -0.67945 -0.3048)
			(stroke
				(width 0.1)
				(type default)
			)
			(layer "B.Fab")
		)
		(fp_line
			(start -0.67945 0.3048)
			(end -0.120396 0.3048)
			(stroke
				(width 0.1)
				(type default)
			)
			(layer "B.Fab")
		)
		(fp_line
			(start -0.67945 -0.3048)
			(end -0.67945 0.3048)
			(stroke
				(width 0.1)
				(type default)
			)
			(layer "B.Fab")
		)
		(pad "1" smd circle
			(at 0.40005 0)
			(size 0 0)
			(layers "B.Cu" "B.Mask" "B.Paste")
			(net "P1V05_PCH_AUX")
		)
		(pad "2" smd circle
			(at -0.40005 0)
			(size 0 0)
			(layers "B.Cu" "B.Mask" "B.Paste")
			(net "P1V05_PCH_PLL_AUX")
		)
	)
	(footprint ""
		(layer "B.Cu")
		(at 312.578242 -39.794688 180)
		(property "Reference" "R1498"
			(at 0 0 0)
			(layer "B.SilkS")
			(hide yes)
			(effects
				(font
					(size 1.27 1.27)
				)
				(justify mirror)
			)
		)
		(property "Value" ""
			(at 0 0 0)
			(layer "B.Fab")
			(effects
				(font
					(size 1.27 1.27)
				)
				(justify mirror)
			)
		)
		(duplicate_pad_numbers_are_jumpers no)
		(fp_line
			(start 0.7874 0.4064)
			(end 0.7874 -0.4064)
			(stroke
				(width 0.1524)
				(type default)
			)
			(layer "B.SilkS")
		)
		(fp_line
			(start 0.7874 -0.4064)
			(end -0.7874 -0.4064)
			(stroke
				(width 0.1524)
				(type default)
			)
			(layer "B.SilkS")
		)
		(fp_line
			(start -0.7874 0.4064)
			(end 0.7874 0.4064)
			(stroke
				(width 0.1524)
				(type default)
			)
			(layer "B.SilkS")
		)
		(fp_line
			(start -0.7874 -0.4064)
			(end -0.7874 0.4064)
			(stroke
				(width 0.1524)
				(type default)
			)
			(layer "B.SilkS")
		)
		(fp_line
			(start 0.67945 0.3048)
			(end 0.67945 -0.305054)
			(stroke
				(width 0.1)
				(type default)
			)
			(layer "B.Fab")
		)
		(fp_line
			(start 0.67945 -0.305054)
			(end 0.12065 -0.305054)
			(stroke
				(width 0.1)
				(type default)
			)
			(layer "B.Fab")
		)
		(fp_line
			(start 0.12065 0.3048)
			(end 0.67945 0.3048)
			(stroke
				(width 0.1)
				(type default)
			)
			(layer "B.Fab")
		)
		(fp_line
			(start 0.12065 0.2794)
			(end 0.12065 0.3048)
			(stroke
				(width 0.1)
				(type default)
			)
			(layer "B.Fab")
		)
		(fp_line
			(start 0.12065 -0.2794)
			(end -0.12065 -0.2794)
			(stroke
				(width 0.1)
				(type default)
			)
			(layer "B.Fab")
		)
		(fp_line
			(start 0.12065 -0.305054)
			(end 0.12065 -0.2794)
			(stroke
				(width 0.1)
				(type default)
			)
			(layer "B.Fab")
		)
		(fp_line
			(start -0.120396 0.3048)
			(end -0.120396 0.2794)
			(stroke
				(width 0.1)
				(type default)
			)
			(layer "B.Fab")
		)
		(fp_line
			(start -0.120396 0.2794)
			(end 0.12065 0.2794)
			(stroke
				(width 0.1)
				(type default)
			)
			(layer "B.Fab")
		)
		(fp_line
			(start -0.12065 -0.2794)
			(end -0.12065 -0.3048)
			(stroke
				(width 0.1)
				(type default)
			)
			(layer "B.Fab")
		)
		(fp_line
			(start -0.12065 -0.3048)
			(end -0.67945 -0.3048)
			(stroke
				(width 0.1)
				(type default)
			)
			(layer "B.Fab")
		)
		(fp_line
			(start -0.67945 0.3048)
			(end -0.120396 0.3048)
			(stroke
				(width 0.1)
				(type default)
			)
			(layer "B.Fab")
		)
		(fp_line
			(start -0.67945 -0.3048)
			(end -0.67945 0.3048)
			(stroke
				(width 0.1)
				(type default)
			)
			(layer "B.Fab")
		)
		(pad "1" smd circle
			(at 0.40005 0)
			(size 0 0)
			(layers "B.Cu" "B.Mask" "B.Paste")
			(net "P1V05_PCH_AUX")
		)
		(pad "2" smd circle
			(at -0.40005 0)
			(size 0 0)
			(layers "B.Cu" "B.Mask" "B.Paste")
			(net "FM_BIOS_ADV_FUNCTIONS")
		)
	)
)
